# S9S_MB_2U (Grand Teton) — schematic netlist excerpt (pin names and nets, part order shuffled) for the footprints in the layout excerpt that follows; sources: Cadence DE-HDL packaged netlist, KiCad conversion of 03242023_DA0F0TMBIJ0_F0T_Motherboard_J_brd_V01_OCP.brd

J111  CONN112_10137002101LF  CONN112_10137002-101LF IO  pkg HSD_F112D8_P2W1-2_RDH  page 142
  A1  = GPU_PEX_STRAP1
  A2  = GND
  A3  = GPU_BASE_ID0
  A4  = GND
  A5  = GPU_PEX_STRAP0
  A6  = GND
  A7  = GPU_FPGA_RST_R_BUF_N
  A8  = GND
  B1  = GND
  B2  = P5E_CPU1_PE0_RX_DN<6>
  B3  = GND
  B4  = P5E_CPU1_PE0_RX_DN<4>
  B5  = GND
  B6  = P5E_CPU1_PE0_RX_DN<2>
  B7  = GND
  B8  = P5E_CPU1_PE0_RX_DN<0>
  C1  = P5E_CPU1_PE0_RX_DN<7>
  C2  = P5E_CPU1_PE0_RX_DP<6>
  C3  = P5E_CPU1_PE0_RX_DN<5>
  C4  = P5E_CPU1_PE0_RX_DP<4>
  C5  = P5E_CPU1_PE0_RX_DP<3>
  C6  = P5E_CPU1_PE0_RX_DP<2>
  C7  = P5E_CPU1_PE0_RX_DP<1>
  C8  = P5E_CPU1_PE0_RX_DP<0>
  D1  = P5E_CPU1_PE0_RX_DP<7>
  D2  = GND
  D3  = P5E_CPU1_PE0_RX_DP<5>
  D4  = GND
  D5  = P5E_CPU1_PE0_RX_DN<3>
  D6  = GND
  D7  = P5E_CPU1_PE0_RX_DN<1>
  D8  = GND
  E1  = GND
  E2  = P5E_CPU1_PE4_RX_DP<9>
  E3  = GND
  E4  = P5E_CPU1_PE4_RX_DP<11>
  E5  = GND
  E6  = P5E_CPU1_PE4_RX_DP<13>
  E7  = GND
  E8  = P5E_CPU1_PE4_RX_DP<15>
  F1  = P5E_CPU1_PE4_RX_DN<8>
  F2  = P5E_CPU1_PE4_RX_DN<9>
  F3  = P5E_CPU1_PE4_RX_DN<10>
  F4  = P5E_CPU1_PE4_RX_DN<11>
  F5  = P5E_CPU1_PE4_RX_DN<12>
  F6  = P5E_CPU1_PE4_RX_DN<13>
  F7  = P5E_CPU1_PE4_RX_DN<14>
  F8  = P5E_CPU1_PE4_RX_DN<15>
  G1  = P5E_CPU1_PE4_RX_DP<8>
  G2  = GND
  G3  = P5E_CPU1_PE4_RX_DP<10>
  G4  = GND
  G5  = P5E_CPU1_PE4_RX_DP<12>
  G6  = GND
  G7  = P5E_CPU1_PE4_RX_DP<14>
  G8  = GND
  H1  = GND
  H2  = P5E_CPU1_PE0_TX_C_DN<6>
  H3  = GND
  H4  = P5E_CPU1_PE0_TX_C_DN<4>
  H5  = GND
  H6  = P5E_CPU1_PE0_TX_C_DN<2>
  H7  = GND
  H8  = P5E_CPU1_PE0_TX_C_DN<0>
  I1  = P5E_CPU1_PE0_TX_C_DN<7>
  I2  = P5E_CPU1_PE0_TX_C_DP<6>
  I3  = P5E_CPU1_PE0_TX_C_DN<5>
  I4  = P5E_CPU1_PE0_TX_C_DP<4>
  I5  = P5E_CPU1_PE0_TX_C_DN<3>
  I6  = P5E_CPU1_PE0_TX_C_DP<2>
  I7  = P5E_CPU1_PE0_TX_C_DN<1>
  I8  = P5E_CPU1_PE0_TX_C_DP<0>
  J1  = P5E_CPU1_PE0_TX_C_DP<7>
  J2  = GND
  J3  = P5E_CPU1_PE0_TX_C_DP<5>
  J4  = GND
  J5  = P5E_CPU1_PE0_TX_C_DP<3>
  J6  = GND
  J7  = P5E_CPU1_PE0_TX_C_DP<1>
  J8  = GND
  K1  = GND
  K2  = P5E_CPU1_PE4_TX_C_DN<9>
  K3  = GND
  K4  = P5E_CPU1_PE4_TX_C_DP<11>
  K5  = GND
  K6  = P5E_CPU1_PE4_TX_C_DN<13>
  K7  = GND
  K8  = P5E_CPU1_PE4_TX_C_DN<15>
  L1  = P5E_CPU1_PE4_TX_C_DN<8>
  L2  = P5E_CPU1_PE4_TX_C_DP<9>
  L3  = P5E_CPU1_PE4_TX_C_DN<10>
  L4  = P5E_CPU1_PE4_TX_C_DN<11>
  L5  = P5E_CPU1_PE4_TX_C_DN<12>
  L6  = P5E_CPU1_PE4_TX_C_DP<13>
  L7  = P5E_CPU1_PE4_TX_C_DN<14>
  L8  = P5E_CPU1_PE4_TX_C_DP<15>
  M1  = P5E_CPU1_PE4_TX_C_DP<8>
  M2  = GND
  M3  = P5E_CPU1_PE4_TX_C_DP<10>
  M4  = GND
  M5  = P5E_CPU1_PE4_TX_C_DP<12>
  M6  = GND
  M7  = P5E_CPU1_PE4_TX_C_DP<14>
  M8  = GND
  N1  = GND
  N2  = GPU_PRSNT_N
  N3  = GND
  N4  = FM_GPU_PWR_EN_R_BUF
  N5  = GND
  N6  = FM_GPU_PWRGD
  N7  = GND
  N8  = GPU_BASE_ID1

(kicad_pcb
	(version 20260206)
	(generator "pcbnew")
	(generator_version "10.0")
	(general
		(thickness 1.6)
		(legacy_teardrops no)
	)
	(paper "A4")
	(title_block
		(title "03242023_DA0F0TMBIJ0_F0T_Motherboard_J_brd_V01_OCP.brd")
		(comment 1 "Grand Teton / footprint 537 of 6105 (J111), pads 1-31 of 48")
	)
	(layers
		(0 "F.Cu" signal "TOP")
		(4 "In1.Cu" signal "GND")
		(6 "In2.Cu" signal "IN1")
		(8 "In3.Cu" signal "GND1")
		(10 "In4.Cu" signal "IN2")
		(12 "In5.Cu" signal "GND2")
		(14 "In6.Cu" signal "IN3")
		(16 "In7.Cu" signal "GND3")
		(18 "In8.Cu" signal "VCC")
		(20 "In9.Cu" signal "VCC1")
		(22 "In10.Cu" signal "GND4")
		(24 "In11.Cu" signal "IN4")
		(26 "In12.Cu" signal "GND5")
		(28 "In13.Cu" signal "IN5")
		(30 "In14.Cu" signal "GND6")
		(32 "In15.Cu" signal "IN6")
		(34 "In16.Cu" signal "GND7")
		(2 "B.Cu" signal "BOTTOM")
		(9 "F.Adhes" user "F.Adhesive")
		(11 "B.Adhes" user "B.Adhesive")
		(13 "F.Paste" user "Package Geometry/Pastemask Top")
		(15 "B.Paste" user "Package Geometry/Pastemask Bottom")
		(5 "F.SilkS" user "Ref Des/Silkscreen Top")
		(7 "B.SilkS" user "Ref Des/Silkscreen Bottom")
		(1 "F.Mask" user "Board Geometry/Soldermask Top")
		(3 "B.Mask" user "Board Geometry/Soldermask Bottom")
		(17 "Dwgs.User" user "User.Drawings")
		(19 "Cmts.User" user "User.Comments")
		(21 "Eco1.User" user "User.Eco1")
		(23 "Eco2.User" user "User.Eco2")
		(25 "Edge.Cuts" user "Board Geometry/Outline")
		(27 "Margin" user)
		(31 "F.CrtYd" user "Package Geometry/Place Bound Top")
		(29 "B.CrtYd" user "Package Geometry/Place Bound Bottom")
		(35 "F.Fab" user "Ref Des/Assembly Top")
		(33 "B.Fab" user "Ref Des/Assembly Bottom")
	)
	(footprint ""
		(layer "F.Cu")
		(at 75.65009 -440.489848)
		(property "Reference" "J111"
			(at 1.96088 23.159212 0)
			(unlocked yes)
			(layer "F.SilkS")
			(effects
				(font
					(size 0.7874 0.5842)
					(thickness 0.1524)
				)
				(justify left)
			)
		)
		(property "Value" ""
			(at 0 0 0)
			(layer "F.Fab")
			(effects
				(font
					(size 1.27 1.27)
				)
			)
		)
		(duplicate_pad_numbers_are_jumpers no)
		(pad "A1" thru_hole rect
			(at 0 0 180)
			(size 0.766318 0.766318)
			(drill 0.359918)
			(layers "*.Cu" "*.Mask")
			(remove_unused_layers no)
			(net "GPU_PEX_STRAP1")
			(clearance 0.0508)
			(thermal_gap 0.0508)
			(padstack
				(mode front_inner_back)
				(layer "Inner"
					(shape circle)
					(size 0.766318 0.766318)
					(clearance 0.0508)
				)
				(layer "B.Cu"
					(shape rect)
					(size 0.766318 0.766318)
					(clearance 0.0508)
				)
			)
		)
		(pad "A2" thru_hole circle
			(at 1.999996 0.199898 180)
			(size 0.906272 0.906272)
			(drill 0.499872)
			(layers "*.Cu" "*.Mask")
			(remove_unused_layers no)
			(net "GND")
			(clearance 0.0508)
			(thermal_gap 0.0508)
		)
		(pad "A3" thru_hole circle
			(at 3.999992 0 180)
			(size 0.766318 0.766318)
			(drill 0.359918)
			(layers "*.Cu" "*.Mask")
			(remove_unused_layers no)
			(net "GPU_BASE_ID0")
			(clearance 0.0508)
			(thermal_gap 0.0508)
		)
		(pad "A4" thru_hole circle
			(at 5.999988 0.199898 180)
			(size 0.906272 0.906272)
			(drill 0.499872)
			(layers "*.Cu" "*.Mask")
			(remove_unused_layers no)
			(net "GND")
			(clearance 0.0508)
			(thermal_gap 0.0508)
		)
		(pad "A5" thru_hole circle
			(at 7.999984 0 180)
			(size 0.766318 0.766318)
			(drill 0.359918)
			(layers "*.Cu" "*.Mask")
			(remove_unused_layers no)
			(net "GPU_PEX_STRAP0")
			(clearance 0.0508)
			(thermal_gap 0.0508)
		)
		(pad "A6" thru_hole circle
			(at 9.99998 0.199898 180)
			(size 0.906272 0.906272)
			(drill 0.499872)
			(layers "*.Cu" "*.Mask")
			(remove_unused_layers no)
			(net "GND")
			(clearance 0.0508)
			(thermal_gap 0.0508)
		)
		(pad "A7" thru_hole circle
			(at 11.999976 0 180)
			(size 0.766318 0.766318)
			(drill 0.359918)
			(layers "*.Cu" "*.Mask")
			(remove_unused_layers no)
			(net "GPU_FPGA_RST_R_BUF_N")
			(clearance 0.0508)
			(thermal_gap 0.0508)
		)
		(pad "A8" thru_hole circle
			(at 13.999972 0.199898 180)
			(size 0.906272 0.906272)
			(drill 0.499872)
			(layers "*.Cu" "*.Mask")
			(remove_unused_layers no)
			(net "GND")
			(clearance 0.0508)
			(thermal_gap 0.0508)
		)
		(pad "B1" thru_hole circle
			(at 0 1.199896 180)
			(size 0.906272 0.906272)
			(drill 0.499872)
			(layers "*.Cu" "*.Mask")
			(remove_unused_layers no)
			(net "GND")
			(clearance 0.0508)
			(thermal_gap 0.0508)
		)
		(pad "B3" thru_hole circle
			(at 3.999992 1.199896 180)
			(size 0.906272 0.906272)
			(drill 0.499872)
			(layers "*.Cu" "*.Mask")
			(remove_unused_layers no)
			(net "GND")
			(clearance 0.0508)
			(thermal_gap 0.0508)
		)
		(pad "B5" thru_hole circle
			(at 7.999984 1.199896 180)
			(size 0.906272 0.906272)
			(drill 0.499872)
			(layers "*.Cu" "*.Mask")
			(remove_unused_layers no)
			(net "GND")
			(clearance 0.0508)
			(thermal_gap 0.0508)
		)
		(pad "B7" thru_hole circle
			(at 11.999976 1.199896 180)
			(size 0.906272 0.906272)
			(drill 0.499872)
			(layers "*.Cu" "*.Mask")
			(remove_unused_layers no)
			(net "GND")
			(clearance 0.0508)
			(thermal_gap 0.0508)
		)
		(pad "D2" thru_hole circle
			(at 1.999996 3.800094 180)
			(size 0.906272 0.906272)
			(drill 0.499872)
			(layers "*.Cu" "*.Mask")
			(remove_unused_layers no)
			(net "GND")
			(clearance 0.0508)
			(thermal_gap 0.0508)
		)
		(pad "D4" thru_hole circle
			(at 5.999988 3.800094 180)
			(size 0.906272 0.906272)
			(drill 0.499872)
			(layers "*.Cu" "*.Mask")
			(remove_unused_layers no)
			(net "GND")
			(clearance 0.0508)
			(thermal_gap 0.0508)
		)
		(pad "D6" thru_hole circle
			(at 9.99998 3.800094 180)
			(size 0.906272 0.906272)
			(drill 0.499872)
			(layers "*.Cu" "*.Mask")
			(remove_unused_layers no)
			(net "GND")
			(clearance 0.0508)
			(thermal_gap 0.0508)
		)
		(pad "D8" thru_hole circle
			(at 13.999972 3.800094 180)
			(size 0.906272 0.906272)
			(drill 0.499872)
			(layers "*.Cu" "*.Mask")
			(remove_unused_layers no)
			(net "GND")
			(clearance 0.0508)
			(thermal_gap 0.0508)
		)
		(pad "E1" thru_hole circle
			(at 0 4.800092 180)
			(size 0.906272 0.906272)
			(drill 0.499872)
			(layers "*.Cu" "*.Mask")
			(remove_unused_layers no)
			(net "GND")
			(clearance 0.0508)
			(thermal_gap 0.0508)
		)
		(pad "E3" thru_hole circle
			(at 3.999992 4.800092 180)
			(size 0.906272 0.906272)
			(drill 0.499872)
			(layers "*.Cu" "*.Mask")
			(remove_unused_layers no)
			(net "GND")
			(clearance 0.0508)
			(thermal_gap 0.0508)
		)
		(pad "E5" thru_hole circle
			(at 7.999984 4.800092 180)
			(size 0.906272 0.906272)
			(drill 0.499872)
			(layers "*.Cu" "*.Mask")
			(remove_unused_layers no)
			(net "GND")
			(clearance 0.0508)
			(thermal_gap 0.0508)
		)
		(pad "E7" thru_hole circle
			(at 11.999976 4.800092 180)
			(size 0.906272 0.906272)
			(drill 0.499872)
			(layers "*.Cu" "*.Mask")
			(remove_unused_layers no)
			(net "GND")
			(clearance 0.0508)
			(thermal_gap 0.0508)
		)
		(pad "G2" thru_hole circle
			(at 1.999996 7.400036 180)
			(size 0.906272 0.906272)
			(drill 0.499872)
			(layers "*.Cu" "*.Mask")
			(remove_unused_layers no)
			(net "GND")
			(clearance 0.0508)
			(thermal_gap 0.0508)
		)
		(pad "G4" thru_hole circle
			(at 5.999988 7.400036 180)
			(size 0.906272 0.906272)
			(drill 0.499872)
			(layers "*.Cu" "*.Mask")
			(remove_unused_layers no)
			(net "GND")
			(clearance 0.0508)
			(thermal_gap 0.0508)
		)
		(pad "G6" thru_hole circle
			(at 9.99998 7.400036 180)
			(size 0.906272 0.906272)
			(drill 0.499872)
			(layers "*.Cu" "*.Mask")
			(remove_unused_layers no)
			(net "GND")
			(clearance 0.0508)
			(thermal_gap 0.0508)
		)
		(pad "G8" thru_hole circle
			(at 13.999972 7.400036 180)
			(size 0.906272 0.906272)
			(drill 0.499872)
			(layers "*.Cu" "*.Mask")
			(remove_unused_layers no)
			(net "GND")
			(clearance 0.0508)
			(thermal_gap 0.0508)
		)
		(pad "H1" thru_hole circle
			(at 0 8.400034 180)
			(size 0.906272 0.906272)
			(drill 0.499872)
			(layers "*.Cu" "*.Mask")
			(remove_unused_layers no)
			(net "GND")
			(clearance 0.0508)
			(thermal_gap 0.0508)
		)
		(pad "H3" thru_hole circle
			(at 3.999992 8.400034 180)
			(size 0.906272 0.906272)
			(drill 0.499872)
			(layers "*.Cu" "*.Mask")
			(remove_unused_layers no)
			(net "GND")
			(clearance 0.0508)
			(thermal_gap 0.0508)
		)
		(pad "H5" thru_hole circle
			(at 7.999984 8.400034 180)
			(size 0.906272 0.906272)
			(drill 0.499872)
			(layers "*.Cu" "*.Mask")
			(remove_unused_layers no)
			(net "GND")
			(clearance 0.0508)
			(thermal_gap 0.0508)
		)
		(pad "H7" thru_hole circle
			(at 11.999976 8.400034 180)
			(size 0.906272 0.906272)
			(drill 0.499872)
			(layers "*.Cu" "*.Mask")
			(remove_unused_layers no)
			(net "GND")
			(clearance 0.0508)
			(thermal_gap 0.0508)
		)
		(pad "J2" thru_hole circle
			(at 1.999996 10.999978 180)
			(size 0.906272 0.906272)
			(drill 0.499872)
			(layers "*.Cu" "*.Mask")
			(remove_unused_layers no)
			(net "GND")
			(clearance 0.0508)
			(thermal_gap 0.0508)
		)
		(pad "J4" thru_hole circle
			(at 5.999988 10.999978 180)
			(size 0.906272 0.906272)
			(drill 0.499872)
			(layers "*.Cu" "*.Mask")
			(remove_unused_layers no)
			(net "GND")
			(clearance 0.0508)
			(thermal_gap 0.0508)
		)
		(pad "J6" thru_hole circle
			(at 9.99998 10.999978 180)
			(size 0.906272 0.906272)
			(drill 0.499872)
			(layers "*.Cu" "*.Mask")
			(remove_unused_layers no)
			(net "GND")
			(clearance 0.0508)
			(thermal_gap 0.0508)
		)
	)
)
